# SCM (Grand Teton) — schematic netlist excerpt (pin names and nets, part order shuffled) for the footprints in the layout excerpt that follows; sources: Cadence DE-HDL packaged netlist, KiCad conversion of 12092022_DA0F0TMDCD0_F0T_Management_Board_D_brd_V3_OCP.brd

R63  Q_RES  0 5% EMPTY  pkg 0402LF  page 11 : A = SGPIO_CLK_1 ; B = GND
PC228  Q_CAP  22UF 10V 20% X6S  pkg C0805  page 52 : A = P3V3_AUX ; B = GND
R343  Q_RES  120 1% CHIP  pkg 0402LF  page 20 : A = GND ; B = M_BMC_DDR4_MCS_N

(kicad_pcb
	(version 20260206)
	(generator "pcbnew")
	(generator_version "10.0")
	(general
		(thickness 1.6)
		(legacy_teardrops no)
	)
	(paper "A4")
	(title_block
		(title "12092022_DA0F0TMDCD0_F0T_Management_Board_D_brd_V3_OCP.brd")
		(comment 1 "Grand Teton / footprints 224-226 of 1440")
	)
	(layers
		(0 "F.Cu" signal "TOP")
		(4 "In1.Cu" signal "GND")
		(6 "In2.Cu" signal "IN1")
		(8 "In3.Cu" signal "GND1")
		(10 "In4.Cu" signal "IN2")
		(12 "In5.Cu" signal "VCC")
		(14 "In6.Cu" signal "VCC1")
		(16 "In7.Cu" signal "IN3")
		(18 "In8.Cu" signal "GND2")
		(20 "In9.Cu" signal "IN4")
		(22 "In10.Cu" signal "GND3")
		(2 "B.Cu" signal "BOTTOM")
		(9 "F.Adhes" user "F.Adhesive")
		(11 "B.Adhes" user "B.Adhesive")
		(13 "F.Paste" user "Package Geometry/Pastemask Top")
		(15 "B.Paste" user "Package Geometry/Pastemask Bottom")
		(5 "F.SilkS" user "Ref Des/Silkscreen Top")
		(7 "B.SilkS" user "Ref Des/Silkscreen Bottom")
		(1 "F.Mask" user "Board Geometry/Soldermask Top")
		(3 "B.Mask" user "Board Geometry/Soldermask Bottom")
		(17 "Dwgs.User" user "User.Drawings")
		(19 "Cmts.User" user "User.Comments")
		(21 "Eco1.User" user "User.Eco1")
		(23 "Eco2.User" user "User.Eco2")
		(25 "Edge.Cuts" user "Board Geometry/Outline")
		(27 "Margin" user)
		(31 "F.CrtYd" user "Package Geometry/Place Bound Top")
		(29 "B.CrtYd" user "Package Geometry/Place Bound Bottom")
		(35 "F.Fab" user "Ref Des/Assembly Top")
		(33 "B.Fab" user "Ref Des/Assembly Bottom")
	)
	(footprint ""
		(layer "F.Cu")
		(at 8.849106 -78.183994 90)
		(property "Reference" "PC228"
			(at 0 0 90)
			(layer "F.SilkS")
			(hide yes)
			(effects
				(font
					(size 1.27 1.27)
				)
			)
		)
		(property "Value" ""
			(at 0 0 90)
			(layer "F.Fab")
			(effects
				(font
					(size 1.27 1.27)
				)
			)
		)
		(duplicate_pad_numbers_are_jumpers no)
		(fp_line
			(start 1.651 -0.8382)
			(end 1.651 0.8382)
			(stroke
				(width 0.1524)
				(type default)
			)
			(layer "F.SilkS")
		)
		(fp_line
			(start -1.651 -0.8382)
			(end 1.651 -0.8382)
			(stroke
				(width 0.1524)
				(type default)
			)
			(layer "F.SilkS")
		)
		(fp_line
			(start 1.651 0.8382)
			(end -1.651 0.8382)
			(stroke
				(width 0.1524)
				(type default)
			)
			(layer "F.SilkS")
		)
		(fp_line
			(start 0 0.8382)
			(end 0 -0.8382)
			(stroke
				(width 0.1524)
				(type default)
			)
			(layer "F.SilkS")
		)
		(fp_line
			(start -1.651 0.8382)
			(end -1.651 -0.8382)
			(stroke
				(width 0.1524)
				(type default)
			)
			(layer "F.SilkS")
		)
		(fp_line
			(start 1.55956 -0.7366)
			(end 1.524 -0.7366)
			(stroke
				(width 0.1)
				(type default)
			)
			(layer "F.Fab")
		)
		(fp_line
			(start 1.524 -0.7366)
			(end -1.524 -0.7366)
			(stroke
				(width 0.1)
				(type default)
			)
			(layer "F.Fab")
		)
		(fp_line
			(start -1.524 -0.7366)
			(end -1.55956 -0.7366)
			(stroke
				(width 0.1)
				(type default)
			)
			(layer "F.Fab")
		)
		(fp_line
			(start -1.55956 -0.7366)
			(end -1.55956 0.7366)
			(stroke
				(width 0.1)
				(type default)
			)
			(layer "F.Fab")
		)
		(fp_line
			(start 1.55956 0.7366)
			(end 1.55956 -0.7366)
			(stroke
				(width 0.1)
				(type default)
			)
			(layer "F.Fab")
		)
		(fp_line
			(start 1.524 0.7366)
			(end 1.55956 0.7366)
			(stroke
				(width 0.1)
				(type default)
			)
			(layer "F.Fab")
		)
		(fp_line
			(start -1.524 0.7366)
			(end 1.524 0.7366)
			(stroke
				(width 0.1)
				(type default)
			)
			(layer "F.Fab")
		)
		(fp_line
			(start -1.55956 0.7366)
			(end -1.524 0.7366)
			(stroke
				(width 0.1)
				(type default)
			)
			(layer "F.Fab")
		)
		(pad "1" smd rect
			(at -0.94996 0 270)
			(size 1.1176 1.3716)
			(layers "F.Cu" "F.Mask" "F.Paste")
			(net "P3V3_AUX")
		)
		(pad "2" smd rect
			(at 0.94996 0 270)
			(size 1.1176 1.3716)
			(layers "F.Cu" "F.Mask" "F.Paste")
			(net "GND")
		)
	)
	(footprint ""
		(layer "F.Cu")
		(at 38.608 -108.966 180)
		(property "Reference" "R63"
			(at 0 0 180)
			(layer "F.SilkS")
			(hide yes)
			(effects
				(font
					(size 1.27 1.27)
				)
			)
		)
		(property "Value" ""
			(at 0 0 180)
			(layer "F.Fab")
			(effects
				(font
					(size 1.27 1.27)
				)
			)
		)
		(duplicate_pad_numbers_are_jumpers no)
		(fp_line
			(start 0.7874 0.4064)
			(end -0.7874 0.4064)
			(stroke
				(width 0.1524)
				(type default)
			)
			(layer "F.SilkS")
		)
		(fp_line
			(start 0.7874 -0.4064)
			(end 0.7874 0.4064)
			(stroke
				(width 0.1524)
				(type default)
			)
			(layer "F.SilkS")
		)
		(fp_line
			(start -0.7874 0.4064)
			(end -0.7874 -0.4064)
			(stroke
				(width 0.1524)
				(type default)
			)
			(layer "F.SilkS")
		)
		(fp_line
			(start -0.7874 -0.4064)
			(end 0.7874 -0.4064)
			(stroke
				(width 0.1524)
				(type default)
			)
			(layer "F.SilkS")
		)
		(fp_line
			(start 0.67945 0.3048)
			(end 0.120396 0.3048)
			(stroke
				(width 0.1)
				(type default)
			)
			(layer "F.Fab")
		)
		(fp_line
			(start 0.67945 -0.3048)
			(end 0.67945 0.3048)
			(stroke
				(width 0.1)
				(type default)
			)
			(layer "F.Fab")
		)
		(fp_line
			(start 0.12065 -0.2794)
			(end 0.12065 -0.3048)
			(stroke
				(width 0.1)
				(type default)
			)
			(layer "F.Fab")
		)
		(fp_line
			(start 0.12065 -0.3048)
			(end 0.67945 -0.3048)
			(stroke
				(width 0.1)
				(type default)
			)
			(layer "F.Fab")
		)
		(fp_line
			(start 0.120396 0.3048)
			(end 0.120396 0.2794)
			(stroke
				(width 0.1)
				(type default)
			)
			(layer "F.Fab")
		)
		(fp_line
			(start 0.120396 0.2794)
			(end -0.12065 0.2794)
			(stroke
				(width 0.1)
				(type default)
			)
			(layer "F.Fab")
		)
		(fp_line
			(start -0.12065 0.3048)
			(end -0.67945 0.3048)
			(stroke
				(width 0.1)
				(type default)
			)
			(layer "F.Fab")
		)
		(fp_line
			(start -0.12065 0.2794)
			(end -0.12065 0.3048)
			(stroke
				(width 0.1)
				(type default)
			)
			(layer "F.Fab")
		)
		(fp_line
			(start -0.12065 -0.2794)
			(end 0.12065 -0.2794)
			(stroke
				(width 0.1)
				(type default)
			)
			(layer "F.Fab")
		)
		(fp_line
			(start -0.12065 -0.305054)
			(end -0.12065 -0.2794)
			(stroke
				(width 0.1)
				(type default)
			)
			(layer "F.Fab")
		)
		(fp_line
			(start -0.67945 0.3048)
			(end -0.67945 -0.305054)
			(stroke
				(width 0.1)
				(type default)
			)
			(layer "F.Fab")
		)
		(fp_line
			(start -0.67945 -0.305054)
			(end -0.12065 -0.305054)
			(stroke
				(width 0.1)
				(type default)
			)
			(layer "F.Fab")
		)
		(pad "1" smd circle
			(at -0.40005 0 180)
			(size 0 0)
			(layers "F.Cu" "F.Mask" "F.Paste")
			(net "SGPIO_CLK_1")
		)
		(pad "2" smd circle
			(at 0.40005 0 180)
			(size 0 0)
			(layers "F.Cu" "F.Mask" "F.Paste")
			(net "GND")
		)
	)
	(footprint ""
		(layer "F.Cu")
		(at 85.29955 -39.347394 180)
		(property "Reference" "R343"
			(at 0 0 180)
			(layer "F.SilkS")
			(hide yes)
			(effects
				(font
					(size 1.27 1.27)
				)
			)
		)
		(property "Value" ""
			(at 0 0 180)
			(layer "F.Fab")
			(effects
				(font
					(size 1.27 1.27)
				)
			)
		)
		(duplicate_pad_numbers_are_jumpers no)
		(fp_line
			(start 0.7874 0.4064)
			(end -0.7874 0.4064)
			(stroke
				(width 0.1524)
				(type default)
			)
			(layer "F.SilkS")
		)
		(fp_line
			(start 0.7874 -0.4064)
			(end 0.7874 0.4064)
			(stroke
				(width 0.1524)
				(type default)
			)
			(layer "F.SilkS")
		)
		(fp_line
			(start -0.7874 0.4064)
			(end -0.7874 -0.4064)
			(stroke
				(width 0.1524)
				(type default)
			)
			(layer "F.SilkS")
		)
		(fp_line
			(start -0.7874 -0.4064)
			(end 0.7874 -0.4064)
			(stroke
				(width 0.1524)
				(type default)
			)
			(layer "F.SilkS")
		)
		(fp_line
			(start 0.67945 0.3048)
			(end 0.120396 0.3048)
			(stroke
				(width 0.1)
				(type default)
			)
			(layer "F.Fab")
		)
		(fp_line
			(start 0.67945 -0.3048)
			(end 0.67945 0.3048)
			(stroke
				(width 0.1)
				(type default)
			)
			(layer "F.Fab")
		)
		(fp_line
			(start 0.12065 -0.2794)
			(end 0.12065 -0.3048)
			(stroke
				(width 0.1)
				(type default)
			)
			(layer "F.Fab")
		)
		(fp_line
			(start 0.12065 -0.3048)
			(end 0.67945 -0.3048)
			(stroke
				(width 0.1)
				(type default)
			)
			(layer "F.Fab")
		)
		(fp_line
			(start 0.120396 0.3048)
			(end 0.120396 0.2794)
			(stroke
				(width 0.1)
				(type default)
			)
			(layer "F.Fab")
		)
		(fp_line
			(start 0.120396 0.2794)
			(end -0.12065 0.2794)
			(stroke
				(width 0.1)
				(type default)
			)
			(layer "F.Fab")
		)
		(fp_line
			(start -0.12065 0.3048)
			(end -0.67945 0.3048)
			(stroke
				(width 0.1)
				(type default)
			)
			(layer "F.Fab")
		)
		(fp_line
			(start -0.12065 0.2794)
			(end -0.12065 0.3048)
			(stroke
				(width 0.1)
				(type default)
			)
			(layer "F.Fab")
		)
		(fp_line
			(start -0.12065 -0.2794)
			(end 0.12065 -0.2794)
			(stroke
				(width 0.1)
				(type default)
			)
			(layer "F.Fab")
		)
		(fp_line
			(start -0.12065 -0.305054)
			(end -0.12065 -0.2794)
			(stroke
				(width 0.1)
				(type default)
			)
			(layer "F.Fab")
		)
		(fp_line
			(start -0.67945 0.3048)
			(end -0.67945 -0.305054)
			(stroke
				(width 0.1)
				(type default)
			)
			(layer "F.Fab")
		)
		(fp_line
			(start -0.67945 -0.305054)
			(end -0.12065 -0.305054)
			(stroke
				(width 0.1)
				(type default)
			)
			(layer "F.Fab")
		)
		(pad "1" smd circle
			(at -0.40005 0 180)
			(size 0 0)
			(layers "F.Cu" "F.Mask" "F.Paste")
			(net "GND")
		)
		(pad "2" smd circle
			(at 0.40005 0 180)
			(size 0 0)
			(layers "F.Cu" "F.Mask" "F.Paste")
			(net "M_BMC_DDR4_MCS_N")
		)
	)
)
